# SCM (Grand Teton) — schematic netlist excerpt (pin names and nets, part order shuffled) for the footprints in the layout excerpt that follows; sources: Cadence DE-HDL packaged netlist, KiCad conversion of 12092022_DA0F0TMDCD0_F0T_Management_Board_D_brd_V3_OCP.brd

R150  Q_RES  33.2 1% CHIP  pkg 0402LF  page 12 : A = SGPIO_LD_1 ; B = SGPIO_BMC_M1_LD

(kicad_pcb
	(version 20260206)
	(generator "pcbnew")
	(generator_version "10.0")
	(general
		(thickness 1.6)
		(legacy_teardrops no)
	)
	(paper "A4")
	(title_block
		(title "12092022_DA0F0TMDCD0_F0T_Management_Board_D_brd_V3_OCP.brd")
		(comment 1 "Grand Teton / footprints 141-141 of 1440")
	)
	(layers
		(0 "F.Cu" signal "TOP")
		(4 "In1.Cu" signal "GND")
		(6 "In2.Cu" signal "IN1")
		(8 "In3.Cu" signal "GND1")
		(10 "In4.Cu" signal "IN2")
		(12 "In5.Cu" signal "VCC")
		(14 "In6.Cu" signal "VCC1")
		(16 "In7.Cu" signal "IN3")
		(18 "In8.Cu" signal "GND2")
		(20 "In9.Cu" signal "IN4")
		(22 "In10.Cu" signal "GND3")
		(2 "B.Cu" signal "BOTTOM")
		(9 "F.Adhes" user "F.Adhesive")
		(11 "B.Adhes" user "B.Adhesive")
		(13 "F.Paste" user "Package Geometry/Pastemask Top")
		(15 "B.Paste" user "Package Geometry/Pastemask Bottom")
		(5 "F.SilkS" user "Ref Des/Silkscreen Top")
		(7 "B.SilkS" user "Ref Des/Silkscreen Bottom")
		(1 "F.Mask" user "Board Geometry/Soldermask Top")
		(3 "B.Mask" user "Board Geometry/Soldermask Bottom")
		(17 "Dwgs.User" user "User.Drawings")
		(19 "Cmts.User" user "User.Comments")
		(21 "Eco1.User" user "User.Eco1")
		(23 "Eco2.User" user "User.Eco2")
		(25 "Edge.Cuts" user "Board Geometry/Outline")
		(27 "Margin" user)
		(31 "F.CrtYd" user "Package Geometry/Place Bound Top")
		(29 "B.CrtYd" user "Package Geometry/Place Bound Bottom")
		(35 "F.Fab" user "Ref Des/Assembly Top")
		(33 "B.Fab" user "Ref Des/Assembly Bottom")
	)
	(footprint ""
		(layer "F.Cu")
		(at 50.8 -30.861 90)
		(property "Reference" "R150"
			(at 0 0 90)
			(layer "F.SilkS")
			(hide yes)
			(effects
				(font
					(size 1.27 1.27)
				)
			)
		)
		(property "Value" ""
			(at 0 0 90)
			(layer "F.Fab")
			(effects
				(font
					(size 1.27 1.27)
				)
			)
		)
		(duplicate_pad_numbers_are_jumpers no)
		(fp_line
			(start 0.7874 -0.4064)
			(end 0.7874 0.4064)
			(stroke
				(width 0.1524)
				(type default)
			)
			(layer "F.SilkS")
		)
		(fp_line
			(start -0.7874 -0.4064)
			(end 0.7874 -0.4064)
			(stroke
				(width 0.1524)
				(type default)
			)
			(layer "F.SilkS")
		)
		(fp_line
			(start 0.7874 0.4064)
			(end -0.7874 0.4064)
			(stroke
				(width 0.1524)
				(type default)
			)
			(layer "F.SilkS")
		)
		(fp_line
			(start -0.7874 0.4064)
			(end -0.7874 -0.4064)
			(stroke
				(width 0.1524)
				(type default)
			)
			(layer "F.SilkS")
		)
		(fp_line
			(start -0.12065 -0.305054)
			(end -0.12065 -0.2794)
			(stroke
				(width 0.1)
				(type default)
			)
			(layer "F.Fab")
		)
		(fp_line
			(start -0.67945 -0.305054)
			(end -0.12065 -0.305054)
			(stroke
				(width 0.1)
				(type default)
			)
			(layer "F.Fab")
		)
		(fp_line
			(start 0.67945 -0.3048)
			(end 0.67945 0.3048)
			(stroke
				(width 0.1)
				(type default)
			)
			(layer "F.Fab")
		)
		(fp_line
			(start 0.12065 -0.3048)
			(end 0.67945 -0.3048)
			(stroke
				(width 0.1)
				(type default)
			)
			(layer "F.Fab")
		)
		(fp_line
			(start 0.12065 -0.2794)
			(end 0.12065 -0.3048)
			(stroke
				(width 0.1)
				(type default)
			)
			(layer "F.Fab")
		)
		(fp_line
			(start -0.12065 -0.2794)
			(end 0.12065 -0.2794)
			(stroke
				(width 0.1)
				(type default)
			)
			(layer "F.Fab")
		)
		(fp_line
			(start 0.120396 0.2794)
			(end -0.12065 0.2794)
			(stroke
				(width 0.1)
				(type default)
			)
			(layer "F.Fab")
		)
		(fp_line
			(start -0.12065 0.2794)
			(end -0.12065 0.3048)
			(stroke
				(width 0.1)
				(type default)
			)
			(layer "F.Fab")
		)
		(fp_line
			(start 0.67945 0.3048)
			(end 0.120396 0.3048)
			(stroke
				(width 0.1)
				(type default)
			)
			(layer "F.Fab")
		)
		(fp_line
			(start 0.120396 0.3048)
			(end 0.120396 0.2794)
			(stroke
				(width 0.1)
				(type default)
			)
			(layer "F.Fab")
		)
		(fp_line
			(start -0.12065 0.3048)
			(end -0.67945 0.3048)
			(stroke
				(width 0.1)
				(type default)
			)
			(layer "F.Fab")
		)
		(fp_line
			(start -0.67945 0.3048)
			(end -0.67945 -0.305054)
			(stroke
				(width 0.1)
				(type default)
			)
			(layer "F.Fab")
		)
		(pad "1" smd circle
			(at -0.40005 0 90)
			(size 0 0)
			(layers "F.Cu" "F.Mask" "F.Paste")
			(net "SGPIO_LD_1")
		)
		(pad "2" smd circle
			(at 0.40005 0 90)
			(size 0 0)
			(layers "F.Cu" "F.Mask" "F.Paste")
			(net "SGPIO_BMC_M1_LD")
		)
	)
)
